(kicad_pcb
	(version 20241229)
	(generator "pcbnew")
	(generator_version "9.0")
	(general
		(thickness 1.599998)
		(legacy_teardrops no)
	)
	(paper "A4")
	(title_block
		(date "2023-02-12")
		(rev "1.1.5")
		(comment 9 "footprint 108 of 473 (U3), pads 1-78 of 484")
	)
	(layers
		(0 "F.Cu" signal)
		(4 "In1.Cu" power "In1.GND")
		(6 "In2.Cu" signal)
		(8 "In3.Cu" power "In3.GND")
		(10 "In4.Cu" power "In4.VCC")
		(12 "In5.Cu" signal)
		(14 "In6.Cu" power "In6.VCC")
		(2 "B.Cu" signal)
		(9 "F.Adhes" user "F.Adhesive")
		(11 "B.Adhes" user "B.Adhesive")
		(13 "F.Paste" user)
		(15 "B.Paste" user)
		(5 "F.SilkS" user "F.Silkscreen")
		(7 "B.SilkS" user "B.Silkscreen")
		(1 "F.Mask" user)
		(3 "B.Mask" user)
		(17 "Dwgs.User" user "User.Drawings")
		(19 "Cmts.User" user "User.Comments")
		(21 "Eco1.User" user "User.Eco1")
		(23 "Eco2.User" user "User.Eco2")
		(25 "Edge.Cuts" user)
		(27 "Margin" user)
		(31 "F.CrtYd" user "F.Courtyard")
		(29 "B.CrtYd" user "B.Courtyard")
		(35 "F.Fab" user)
		(33 "B.Fab" user)
	)
	(footprint "antmicro-footprints:BGA-484_23x23mm_Layout22x22_P1mm_FBG484"
		(locked yes)
		(layer "F.Cu")
		(at 169.036328 95.997157 -90)
		(property "Reference" "U3"
			(at -11.8 -12 270)
			(layer "F.SilkS")
			(effects
				(font
					(size 0.7 0.7)
					(thickness 0.15)
				)
				(justify left bottom)
			)
		)
		(property "Value" "XC7K70T-FBG484"
			(at -10.4 0.4 270)
			(layer "F.Fab")
			(effects
				(font
					(size 0.7 0.7)
					(thickness 0.15)
				)
				(justify left bottom)
			)
		)
		(property "Description" "Kintex®-7 Field Programmable Gate Array (FPGA) IC 285 484-BBGA, FCBGA"
			(at 0 0 270)
			(layer "F.Fab")
			(hide yes)
			(effects
				(font
					(size 1.27 1.27)
					(thickness 0.15)
				)
			)
		)
		(property "Author" "Antmicro"
			(at 73.039171 265.033485 0)
			(layer "F.Fab")
			(hide yes)
			(effects
				(font
					(size 1 1)
					(thickness 0.15)
				)
			)
		)
		(property "License" "Apache-2.0"
			(at 73.039171 265.033485 0)
			(layer "F.Fab")
			(hide yes)
			(effects
				(font
					(size 1 1)
					(thickness 0.15)
				)
			)
		)
		(property "MPN" "XC7K70T-1FBG484C"
			(at 73.039171 265.033485 0)
			(layer "F.Fab")
			(hide yes)
			(effects
				(font
					(size 1 1)
					(thickness 0.15)
				)
			)
		)
		(property "Manufacturer" "AMD-Xilinx"
			(at 73.039171 265.033485 0)
			(layer "F.Fab")
			(hide yes)
			(effects
				(font
					(size 1 1)
					(thickness 0.15)
				)
			)
		)
		(sheetname "FPGA Banks")
		(sheetfile "fpga-banks.kicad_sch")
		(attr smd)
		(pad "A1" smd circle
			(at -10.5 -10.5 270)
			(size 0.51 0.51)
			(layers "F.Cu" "F.Mask" "F.Paste")
			(net 5 "GND")
			(pinfunction "GND")
			(pintype "power_in")
		)
		(pad "A2" smd circle
			(at -9.5 -10.5 270)
			(size 0.51 0.51)
			(layers "F.Cu" "F.Mask" "F.Paste")
			(net 271 "unconnected-(U3A-MGTAVTT-PadA2)")
			(pinfunction "MGTAVTT")
			(pintype "power_in+no_connect")
		)
		(pad "A3" smd circle
			(at -8.5 -10.5 270)
			(size 0.51 0.51)
			(layers "F.Cu" "F.Mask" "F.Paste")
			(net 272 "unconnected-(U3C-MGTXTXN3_115-PadA3)")
			(pinfunction "MGTXTXN3_115")
			(pintype "bidirectional+no_connect")
		)
		(pad "A4" smd circle
			(at -7.5 -10.5 270)
			(size 0.51 0.51)
			(layers "F.Cu" "F.Mask" "F.Paste")
			(net 274 "unconnected-(U3C-MGTXTXP3_115-PadA4)")
			(pinfunction "MGTXTXP3_115")
			(pintype "bidirectional+no_connect")
		)
		(pad "A5" smd circle
			(at -6.5 -10.5 270)
			(size 0.51 0.51)
			(layers "F.Cu" "F.Mask" "F.Paste")
			(net 5 "GND")
			(pinfunction "GND")
			(pintype "passive")
		)
		(pad "A6" smd circle
			(at -5.5 -10.5 270)
			(size 0.51 0.51)
			(layers "F.Cu" "F.Mask" "F.Paste")
			(net 275 "unconnected-(U3A-MGTAVCC-PadA6)")
			(pinfunction "MGTAVCC")
			(pintype "power_in+no_connect")
		)
		(pad "A7" smd circle
			(at -4.5 -10.5 270)
			(size 0.51 0.51)
			(layers "F.Cu" "F.Mask" "F.Paste")
			(net 5 "GND")
			(pinfunction "GND")
			(pintype "passive")
		)
		(pad "A8" smd circle
			(at -3.5 -10.5 270)
			(size 0.51 0.51)
			(layers "F.Cu" "F.Mask" "F.Paste")
			(net 57 "USR_LED3")
			(pinfunction "IO_L21N_T3_DQS_16")
			(pintype "bidirectional")
		)
		(pad "A9" smd circle
			(at -2.5 -10.5 270)
			(size 0.51 0.51)
			(layers "F.Cu" "F.Mask" "F.Paste")
			(net 276 "unconnected-(U3F-IO_L21P_T3_DQS_16-PadA9)")
			(pinfunction "IO_L21P_T3_DQS_16")
			(pintype "bidirectional+no_connect")
		)
		(pad "A10" smd circle
			(at -1.5 -10.5 270)
			(size 0.51 0.51)
			(layers "F.Cu" "F.Mask" "F.Paste")
			(net 277 "unconnected-(U3F-IO_L23N_T3_16-PadA10)")
			(pinfunction "IO_L23N_T3_16")
			(pintype "bidirectional+no_connect")
		)
		(pad "A11" smd circle
			(at -0.5 -10.5 270)
			(size 0.51 0.51)
			(layers "F.Cu" "F.Mask" "F.Paste")
			(net 278 "unconnected-(U3F-IO_L23P_T3_16-PadA11)")
			(pinfunction "IO_L23P_T3_16")
			(pintype "bidirectional+no_connect")
		)
		(pad "A12" smd circle
			(at 0.5 -10.5 270)
			(size 0.51 0.51)
			(layers "F.Cu" "F.Mask" "F.Paste")
			(net 5 "GND")
			(pinfunction "GND")
			(pintype "passive")
		)
		(pad "A13" smd circle
			(at 1.5 -10.5 270)
			(size 0.51 0.51)
			(layers "F.Cu" "F.Mask" "F.Paste")
			(net 31 "ETH_TX_EN")
			(pinfunction "IO_L4P_T0_AD9P_15")
			(pintype "bidirectional")
		)
		(pad "A14" smd circle
			(at 2.5 -10.5 270)
			(size 0.51 0.51)
			(layers "F.Cu" "F.Mask" "F.Paste")
			(net 33 "ETH_RXD3")
			(pinfunction "IO_L4N_T0_AD9N_15")
			(pintype "bidirectional")
		)
		(pad "A15" smd circle
			(at 3.5 -10.5 270)
			(size 0.51 0.51)
			(layers "F.Cu" "F.Mask" "F.Paste")
			(net 23 "ETH_RXD1")
			(pinfunction "IO_L9N_T1_DQS_AD11N_15")
			(pintype "bidirectional")
		)
		(pad "A16" smd circle
			(at 4.5 -10.5 270)
			(size 0.51 0.51)
			(layers "F.Cu" "F.Mask" "F.Paste")
			(net 34 "ETH_RX_DV")
			(pinfunction "IO_L8N_T1_AD3N_15")
			(pintype "bidirectional")
		)
		(pad "A17" smd circle
			(at 5.5 -10.5 270)
			(size 0.51 0.51)
			(layers "F.Cu" "F.Mask" "F.Paste")
			(net 459 "3V3_SYS")
			(pinfunction "VCCO_15")
			(pintype "power_in")
		)
		(pad "A18" smd circle
			(at 6.5 -10.5 270)
			(size 0.51 0.51)
			(layers "F.Cu" "F.Mask" "F.Paste")
			(net 29 "ETH_TXD3")
			(pinfunction "IO_L10N_T1_AD4N_15")
			(pintype "bidirectional")
		)
		(pad "A19" smd circle
			(at 7.5 -10.5 270)
			(size 0.51 0.51)
			(layers "F.Cu" "F.Mask" "F.Paste")
			(net 28 "ETH_TXD2")
			(pinfunction "IO_L20N_T3_A19_15")
			(pintype "bidirectional")
		)
		(pad "A20" smd circle
			(at 8.5 -10.5 270)
			(size 0.51 0.51)
			(layers "F.Cu" "F.Mask" "F.Paste")
			(net 279 "unconnected-(U3G-IO_L22P_T3_A17_15-PadA20)")
			(pinfunction "IO_L22P_T3_A17_15")
			(pintype "bidirectional+no_connect")
		)
		(pad "A21" smd circle
			(at 9.5 -10.5 270)
			(size 0.51 0.51)
			(layers "F.Cu" "F.Mask" "F.Paste")
			(net 280 "unconnected-(U3G-IO_L22N_T3_A16_15-PadA21)")
			(pinfunction "IO_L22N_T3_A16_15")
			(pintype "bidirectional+no_connect")
		)
		(pad "A22" smd circle
			(at 10.5 -10.5 270)
			(size 0.51 0.51)
			(layers "F.Cu" "F.Mask" "F.Paste")
			(net 5 "GND")
			(pinfunction "GND")
			(pintype "passive")
		)
		(pad "AA1" smd circle
			(at -10.5 9.5 270)
			(size 0.51 0.51)
			(layers "F.Cu" "F.Mask" "F.Paste")
			(net 333 "DQ10_A")
			(pinfunction "IO_L22P_T3_34")
			(pintype "bidirectional")
		)
		(pad "AA2" smd circle
			(at -9.5 9.5 270)
			(size 0.51 0.51)
			(layers "F.Cu" "F.Mask" "F.Paste")
			(net 5 "GND")
			(pinfunction "GND")
			(pintype "passive")
		)
		(pad "AA3" smd circle
			(at -8.5 9.5 270)
			(size 0.51 0.51)
			(layers "F.Cu" "F.Mask" "F.Paste")
			(net 70 "CA3_A")
			(pinfunction "IO_L23P_T3_34")
			(pintype "bidirectional")
		)
		(pad "AA4" smd circle
			(at -7.5 9.5 270)
			(size 0.51 0.51)
			(layers "F.Cu" "F.Mask" "F.Paste")
			(net 71 "CA2_A")
			(pinfunction "IO_L24P_T3_34")
			(pintype "bidirectional")
		)
		(pad "AA5" smd circle
			(at -6.5 9.5 270)
			(size 0.51 0.51)
			(layers "F.Cu" "F.Mask" "F.Paste")
			(net 281 "unconnected-(U3E-IO_L1P_T0_33-PadAA5)")
			(pinfunction "IO_L1P_T0_33")
			(pintype "bidirectional+no_connect")
		)
		(pad "AA6" smd circle
			(at -5.5 9.5 270)
			(size 0.51 0.51)
			(layers "F.Cu" "F.Mask" "F.Paste")
			(net 282 "unconnected-(U3E-IO_L3P_T0_DQS_33-PadAA6)")
			(pinfunction "IO_L3P_T0_DQS_33")
			(pintype "bidirectional+no_connect")
		)
		(pad "AA7" smd circle
			(at -4.5 9.5 270)
			(size 0.51 0.51)
			(layers "F.Cu" "F.Mask" "F.Paste")
			(net 66 "VDDQ")
			(pinfunction "VCCO_33")
			(pintype "power_in")
		)
		(pad "AA8" smd circle
			(at -3.5 9.5 270)
			(size 0.51 0.51)
			(layers "F.Cu" "F.Mask" "F.Paste")
			(net 283 "unconnected-(U3E-IO_L5N_T0_33-PadAA8)")
			(pinfunction "IO_L5N_T0_33")
			(pintype "bidirectional+no_connect")
		)
		(pad "AA9" smd circle
			(at -2.5 9.5 270)
			(size 0.51 0.51)
			(layers "F.Cu" "F.Mask" "F.Paste")
			(net 284 "unconnected-(U3E-IO_L5P_T0_33-PadAA9)")
			(pinfunction "IO_L5P_T0_33")
			(pintype "bidirectional+no_connect")
		)
		(pad "AA10" smd circle
			(at -1.5 9.5 270)
			(size 0.51 0.51)
			(layers "F.Cu" "F.Mask" "F.Paste")
			(net 285 "unconnected-(U3E-IO_L4P_T0_33-PadAA10)")
			(pinfunction "IO_L4P_T0_33")
			(pintype "bidirectional+no_connect")
		)
		(pad "AA11" smd circle
			(at -0.5 9.5 270)
			(size 0.51 0.51)
			(layers "F.Cu" "F.Mask" "F.Paste")
			(net 481 "IO_AA11")
			(pinfunction "IO_L20P_T3_33")
			(pintype "bidirectional")
		)
		(pad "AA12" smd circle
			(at 0.5 9.5 270)
			(size 0.51 0.51)
			(layers "F.Cu" "F.Mask" "F.Paste")
			(net 5 "GND")
			(pinfunction "GND")
			(pintype "passive")
		)
		(pad "AA13" smd circle
			(at 1.5 9.5 270)
			(size 0.51 0.51)
			(layers "F.Cu" "F.Mask" "F.Paste")
			(net 286 "unconnected-(U3E-IO_L21N_T3_DQS_33-PadAA13)")
			(pinfunction "IO_L21N_T3_DQS_33")
			(pintype "bidirectional+no_connect")
		)
		(pad "AA14" smd circle
			(at 2.5 9.5 270)
			(size 0.51 0.51)
			(layers "F.Cu" "F.Mask" "F.Paste")
			(net 500 "HR_DQ2")
			(pinfunction "IO_L18P_T2_13")
			(pintype "bidirectional")
		)
		(pad "AA15" smd circle
			(at 3.5 9.5 270)
			(size 0.51 0.51)
			(layers "F.Cu" "F.Mask" "F.Paste")
			(net 490 "HR_DQ1")
			(pinfunction "IO_L18N_T2_13")
			(pintype "bidirectional")
		)
		(pad "AA16" smd circle
			(at 4.5 9.5 270)
			(size 0.51 0.51)
			(layers "F.Cu" "F.Mask" "F.Paste")
			(net 489 "HR_CS")
			(pinfunction "IO_L17P_T2_13")
			(pintype "bidirectional")
		)
		(pad "AA17" smd circle
			(at 5.5 9.5 270)
			(size 0.51 0.51)
			(layers "F.Cu" "F.Mask" "F.Paste")
			(net 459 "3V3_SYS")
			(pinfunction "VCCO_13")
			(pintype "power_in")
		)
		(pad "AA18" smd circle
			(at 6.5 9.5 270)
			(size 0.51 0.51)
			(layers "F.Cu" "F.Mask" "F.Paste")
			(net 451 "UART0_RX")
			(pinfunction "IO_L15P_T2_DQS_13")
			(pintype "bidirectional")
		)
		(pad "AA19" smd circle
			(at 7.5 9.5 270)
			(size 0.51 0.51)
			(layers "F.Cu" "F.Mask" "F.Paste")
			(net 287 "unconnected-(U3I-IO_L10P_T1_13-PadAA19)")
			(pinfunction "IO_L10P_T1_13")
			(pintype "bidirectional+no_connect")
		)
		(pad "AA20" smd circle
			(at 8.5 9.5 270)
			(size 0.51 0.51)
			(layers "F.Cu" "F.Mask" "F.Paste")
			(net 457 "UART1_TX")
			(pinfunction "IO_L8P_T1_13")
			(pintype "bidirectional")
		)
		(pad "AA21" smd circle
			(at 9.5 9.5 270)
			(size 0.51 0.51)
			(layers "F.Cu" "F.Mask" "F.Paste")
			(net 646 "FPGA_AA21_BALL")
			(pinfunction "IO_L9P_T1_DQS_13")
			(pintype "bidirectional")
		)
		(pad "AA22" smd circle
			(at 10.5 9.5 270)
			(size 0.51 0.51)
			(layers "F.Cu" "F.Mask" "F.Paste")
			(net 5 "GND")
			(pinfunction "GND")
			(pintype "passive")
		)
		(pad "AB1" smd circle
			(at -10.5 10.5 270)
			(size 0.51 0.51)
			(layers "F.Cu" "F.Mask" "F.Paste")
			(net 332 "DQ11_A")
			(pinfunction "IO_L22N_T3_34")
			(pintype "bidirectional")
		)
		(pad "AB2" smd circle
			(at -9.5 10.5 270)
			(size 0.51 0.51)
			(layers "F.Cu" "F.Mask" "F.Paste")
			(net 68 "CA5_A")
			(pinfunction "IO_L23N_T3_34")
			(pintype "bidirectional")
		)
		(pad "AB3" smd circle
			(at -8.5 10.5 270)
			(size 0.51 0.51)
			(layers "F.Cu" "F.Mask" "F.Paste")
			(net 69 "CA4_A")
			(pinfunction "IO_L24N_T3_34")
			(pintype "bidirectional")
		)
		(pad "AB4" smd circle
			(at -7.5 10.5 270)
			(size 0.51 0.51)
			(layers "F.Cu" "F.Mask" "F.Paste")
			(net 66 "VDDQ")
			(pinfunction "VCCO_34")
			(pintype "power_in")
		)
		(pad "AB5" smd circle
			(at -6.5 10.5 270)
			(size 0.51 0.51)
			(layers "F.Cu" "F.Mask" "F.Paste")
			(net 288 "unconnected-(U3E-IO_L1N_T0_33-PadAB5)")
			(pinfunction "IO_L1N_T0_33")
			(pintype "bidirectional+no_connect")
		)
		(pad "AB6" smd circle
			(at -5.5 10.5 270)
			(size 0.51 0.51)
			(layers "F.Cu" "F.Mask" "F.Paste")
			(net 289 "unconnected-(U3E-IO_L3N_T0_DQS_33-PadAB6)")
			(pinfunction "IO_L3N_T0_DQS_33")
			(pintype "bidirectional+no_connect")
		)
		(pad "AB7" smd circle
			(at -4.5 10.5 270)
			(size 0.51 0.51)
			(layers "F.Cu" "F.Mask" "F.Paste")
			(net 290 "unconnected-(U3E-IO_L2N_T0_33-PadAB7)")
			(pinfunction "IO_L2N_T0_33")
			(pintype "bidirectional+no_connect")
		)
		(pad "AB8" smd circle
			(at -3.5 10.5 270)
			(size 0.51 0.51)
			(layers "F.Cu" "F.Mask" "F.Paste")
			(net 291 "unconnected-(U3E-IO_L2P_T0_33-PadAB8)")
			(pinfunction "IO_L2P_T0_33")
			(pintype "bidirectional+no_connect")
		)
		(pad "AB9" smd circle
			(at -2.5 10.5 270)
			(size 0.51 0.51)
			(layers "F.Cu" "F.Mask" "F.Paste")
			(net 5 "GND")
			(pinfunction "GND")
			(pintype "passive")
		)
		(pad "AB10" smd circle
			(at -1.5 10.5 270)
			(size 0.51 0.51)
			(layers "F.Cu" "F.Mask" "F.Paste")
			(net 480 "IO_AB10")
			(pinfunction "IO_L4N_T0_33")
			(pintype "bidirectional")
		)
		(pad "AB11" smd circle
			(at -0.5 10.5 270)
			(size 0.51 0.51)
			(layers "F.Cu" "F.Mask" "F.Paste")
			(net 479 "IO_AB11")
			(pinfunction "IO_L20N_T3_33")
			(pintype "bidirectional")
		)
		(pad "AB12" smd circle
			(at 0.5 10.5 270)
			(size 0.51 0.51)
			(layers "F.Cu" "F.Mask" "F.Paste")
			(net 292 "unconnected-(U3E-IO_L22N_T3_33-PadAB12)")
			(pinfunction "IO_L22N_T3_33")
			(pintype "bidirectional+no_connect")
		)
		(pad "AB13" smd circle
			(at 1.5 10.5 270)
			(size 0.51 0.51)
			(layers "F.Cu" "F.Mask" "F.Paste")
			(net 293 "unconnected-(U3E-IO_L22P_T3_33-PadAB13)")
			(pinfunction "IO_L22P_T3_33")
			(pintype "bidirectional+no_connect")
		)
		(pad "AB14" smd circle
			(at 2.5 10.5 270)
			(size 0.51 0.51)
			(layers "F.Cu" "F.Mask" "F.Paste")
			(net 459 "3V3_SYS")
			(pinfunction "VCCO_13")
			(pintype "passive")
		)
		(pad "AB15" smd circle
			(at 3.5 10.5 270)
			(size 0.51 0.51)
			(layers "F.Cu" "F.Mask" "F.Paste")
			(net 498 "HR_CKP")
			(pinfunction "IO_L16P_T2_13")
			(pintype "bidirectional")
		)
		(pad "AB16" smd circle
			(at 4.5 10.5 270)
			(size 0.51 0.51)
			(layers "F.Cu" "F.Mask" "F.Paste")
			(net 493 "HR_CKN")
			(pinfunction "IO_L16N_T2_13")
			(pintype "bidirectional")
		)
		(pad "AB17" smd circle
			(at 5.5 10.5 270)
			(size 0.51 0.51)
			(layers "F.Cu" "F.Mask" "F.Paste")
			(net 449 "AUX_JTAG_RST")
			(pinfunction "IO_L17N_T2_13")
			(pintype "bidirectional")
		)
		(pad "AB18" smd circle
			(at 6.5 10.5 270)
			(size 0.51 0.51)
			(layers "F.Cu" "F.Mask" "F.Paste")
			(net 453 "UART0_TX")
			(pinfunction "IO_L15N_T2_DQS_13")
			(pintype "bidirectional")
		)
		(pad "AB19" smd circle
			(at 7.5 10.5 270)
			(size 0.51 0.51)
			(layers "F.Cu" "F.Mask" "F.Paste")
			(net 5 "GND")
			(pinfunction "GND")
			(pintype "passive")
		)
		(pad "AB20" smd circle
			(at 8.5 10.5 270)
			(size 0.51 0.51)
			(layers "F.Cu" "F.Mask" "F.Paste")
			(net 455 "UART1_RX")
			(pinfunction "IO_L10N_T1_13")
			(pintype "bidirectional")
		)
		(pad "AB21" smd circle
			(at 9.5 10.5 270)
			(size 0.51 0.51)
			(layers "F.Cu" "F.Mask" "F.Paste")
			(net 644 "FPGA_AB21_BALL")
			(pinfunction "IO_L8N_T1_13")
			(pintype "bidirectional")
		)
		(pad "AB22" smd circle
			(at 10.5 10.5 270)
			(size 0.51 0.51)
			(layers "F.Cu" "F.Mask" "F.Paste")
			(net 643 "FPGA_AB22_BALL")
			(pinfunction "IO_L9N_T1_DQS_13")
			(pintype "bidirectional")
		)
		(pad "B1" smd circle
			(at -10.5 -9.5 270)
			(size 0.51 0.51)
			(layers "F.Cu" "F.Mask" "F.Paste")
			(net 294 "unconnected-(U3C-MGTXTXN2_115-PadB1)")
			(pinfunction "MGTXTXN2_115")
			(pintype "bidirectional+no_connect")
		)
		(pad "B2" smd circle
			(at -9.5 -9.5 270)
			(size 0.51 0.51)
			(layers "F.Cu" "F.Mask" "F.Paste")
			(net 295 "unconnected-(U3C-MGTXTXP2_115-PadB2)")
			(pinfunction "MGTXTXP2_115")
			(pintype "bidirectional+no_connect")
		)
		(pad "B3" smd circle
			(at -8.5 -9.5 270)
			(size 0.51 0.51)
			(layers "F.Cu" "F.Mask" "F.Paste")
			(net 5 "GND")
			(pinfunction "GND")
			(pintype "passive")
		)
		(pad "B4" smd circle
			(at -7.5 -9.5 270)
			(size 0.51 0.51)
			(layers "F.Cu" "F.Mask" "F.Paste")
			(net 5 "GND")
			(pinfunction "GND")
			(pintype "passive")
		)
		(pad "B5" smd circle
			(at -6.5 -9.5 270)
			(size 0.51 0.51)
			(layers "F.Cu" "F.Mask" "F.Paste")
			(net 296 "unconnected-(U3C-MGTXRXN3_115-PadB5)")
			(pinfunction "MGTXRXN3_115")
			(pintype "bidirectional+no_connect")
		)
		(pad "B6" smd circle
			(at -5.5 -9.5 270)
			(size 0.51 0.51)
			(layers "F.Cu" "F.Mask" "F.Paste")
			(net 297 "unconnected-(U3C-MGTXRXP3_115-PadB6)")
			(pinfunction "MGTXRXP3_115")
			(pintype "bidirectional+no_connect")
		)
		(pad "B7" smd circle
			(at -4.5 -9.5 270)
			(size 0.51 0.51)
			(layers "F.Cu" "F.Mask" "F.Paste")
			(net 5 "GND")
			(pinfunction "GND")
			(pintype "passive")
		)
		(pad "B8" smd circle
			(at -3.5 -9.5 270)
			(size 0.51 0.51)
			(layers "F.Cu" "F.Mask" "F.Paste")
			(net 391 "USR_BTN2")
			(pinfunction "IO_L22N_T3_16")
			(pintype "bidirectional")
		)
		(pad "B9" smd circle
			(at -2.5 -9.5 270)
			(size 0.51 0.51)
			(layers "F.Cu" "F.Mask" "F.Paste")
			(net 5 "GND")
			(pinfunction "GND")
			(pintype "passive")
		)
		(pad "B10" smd circle
			(at -1.5 -9.5 270)
			(size 0.51 0.51)
			(layers "F.Cu" "F.Mask" "F.Paste")
			(net 298 "unconnected-(U3F-IO_L20N_T3_16-PadB10)")
			(pinfunction "IO_L20N_T3_16")
			(pintype "bidirectional+no_connect")
		)
		(pad "B11" smd circle
			(at -0.5 -9.5 270)
			(size 0.51 0.51)
			(layers "F.Cu" "F.Mask" "F.Paste")
			(net 299 "unconnected-(U3F-IO_L20P_T3_16-PadB11)")
			(pinfunction "IO_L20P_T3_16")
			(pintype "bidirectional+no_connect")
		)
		(pad "B12" smd circle
			(at 0.5 -9.5 270)
			(size 0.51 0.51)
			(layers "F.Cu" "F.Mask" "F.Paste")
			(net 300 "unconnected-(U3G-IO_L2N_T0_AD8N_15-PadB12)")
			(pinfunction "IO_L2N_T0_AD8N_15")
			(pintype "bidirectional+no_connect")
		)
	)
)
